#ISCELL
  mstr_misc dns *
  *
#ISCELL
  pure_quanta quanta_title_block_c *
  *
#ISCELL
  pure_quanta_power p1v0_aux *
  page146_i1
#CELL
  pure_quanta mosfet_pch_gds_esd_protected *
  page146_i10
#CELL
  pure_quanta q_res *
  page146_i11
#CELL
  pure_quanta q_res *
  page146_i12
#ISCELL
  pure_quanta_power universal_gnd *
  page146_i13
#CELL
  pure_quanta q_res *
  page146_i14
#ISCELL
  pure_quanta_power universal_gnd *
  page146_i15
#CELL
  pure_quanta mosfet_nch_1d3s *
  page146_i16
#ISCELL
  pure_quanta_power universal_gnd *
  page146_i17
#ISCELL
  pure_quanta_power p1v0_aux *
  page146_i18
#CELL
  pure_quanta q_res *
  page146_i19
#CELL
  pure_quanta q_res *
  page146_i2
#CELL
  pure_quanta q_res *
  page146_i21
#CELL
  pure_quanta mosfet_nch_1d3s *
  page146_i22
#CELL
  pure_quanta mosfet_pch_gds_esd_protected *
  page146_i23
#ISCELL
  pure_quanta_power p1v0_aux *
  page146_i24
#CELL
  pure_quanta schottky_dual_12a_3c *
  page146_i25
#ISCELL
  pure_quanta_power universal_gnd *
  page146_i27
#CELL
  pure_quanta q_res *
  page146_i28
#ISCELL
  pure_quanta_power universal_gnd *
  page146_i29
#CELL
  pure_quanta q_res *
  page146_i3
#CELL
  pure_quanta q_cap *
  page146_i30
#ISCELL
  pure_quanta_power universal_gnd *
  page146_i31
#ISCELL
  pure_quanta_power universal_gnd *
  page146_i33
#ISCELL
  pure_quanta_power p1v0_aux *
  page146_i34
#CELL
  pure_quanta q_res *
  page146_i35
#CELL
  pure_quanta q_res *
  page146_i36
#ISCELL
  pure_quanta_power universal_gnd *
  page146_i37
#CELL
  pure_quanta q_res *
  page146_i38
#CELL
  pure_quanta q_res *
  page146_i39
#ISCELL
  pure_quanta_power universal_gnd *
  page146_i4
#ISCELL
  pure_quanta_power p1v0_aux *
  page146_i40
#CELL
  pure_quanta schottky_dual_12a_3c *
  page146_i5
#CELL
  pure_quanta q_cap *
  page146_i6
#ISCELL
  pure_quanta_power universal_gnd *
  page146_i7
#ISCELL
  pure_quanta_power p1v0_aux *
  page146_i9
